(kicad_pcb
	(version 20260206)
	(generator "pcbnew")
	(generator_version "10.0")
	(general
		(thickness 1.6)
		(legacy_teardrops no)
	)
	(paper "A4")
	(title_block
		(title "panther-plus-userver — 13130-1b_20150205.brd")
		(comment 1 "Honey Badger (Wiwynn) / footprint 1214 of 1509 (DIMM3), pads 135-141 of 210")
	)
	(layers
		(0 "F.Cu" signal "TOP")
		(4 "In1.Cu" signal "L2")
		(6 "In2.Cu" signal "L3")
		(8 "In3.Cu" signal "L4")
		(10 "In4.Cu" signal "L5")
		(12 "In5.Cu" signal "L6")
		(14 "In6.Cu" signal "L7")
		(16 "In7.Cu" signal "L8")
		(18 "In8.Cu" signal "L9")
		(20 "In9.Cu" signal "L10")
		(22 "In10.Cu" signal "L11")
		(2 "B.Cu" signal "BOTTOM")
		(9 "F.Adhes" user "F.Adhesive")
		(11 "B.Adhes" user "B.Adhesive")
		(13 "F.Paste" user "Package Geometry/Pastemask Top")
		(15 "B.Paste" user "Package Geometry/Pastemask Bottom")
		(5 "F.SilkS" user "Ref Des/Silkscreen Top")
		(7 "B.SilkS" user "Ref Des/Silkscreen Bottom")
		(1 "F.Mask" user "Board Geometry/Soldermask Top")
		(3 "B.Mask" user "Board Geometry/Soldermask Bottom")
		(17 "Dwgs.User" user "User.Drawings")
		(19 "Cmts.User" user "User.Comments")
		(21 "Eco1.User" user "User.Eco1")
		(23 "Eco2.User" user "User.Eco2")
		(25 "Edge.Cuts" user "Board Geometry/Outline")
		(27 "Margin" user)
		(31 "F.CrtYd" user "Package Geometry/Place Bound Top")
		(29 "B.CrtYd" user "Package Geometry/Place Bound Bottom")
		(35 "F.Fab" user "Ref Des/Assembly Top")
		(33 "B.Fab" user "Ref Des/Assembly Bottom")
	)
	(footprint ""
		(layer "B.Cu")
		(at 159.999934 -5.790692)
		(property "Reference" "DIMM3"
			(at 0 0 0)
			(layer "B.SilkS")
			(hide yes)
			(effects
				(font
					(size 1.27 1.27)
				)
				(justify mirror)
			)
		)
		(property "Value" "DDR3-204P-142-COLAY-1-GP-U"
			(at 41.312338 -16.676878 0)
			(unlocked yes)
			(layer "B.Fab")
			(hide yes)
			(effects
				(font
					(size 1.016 1.016)
					(thickness 0.1524)
				)
				(justify mirror)
			)
		)
		(property "Device Type" "AS0A626-J8R6-7H-COLAY-1"
			(at 41.312338 -18.200878 0)
			(unlocked yes)
			(layer "B.Fab")
			(hide yes)
			(effects
				(font
					(size 1.016 1.016)
					(thickness 0.1524)
				)
				(justify mirror)
			)
		)
		(duplicate_pad_numbers_are_jumpers no)
		(pad "133" smd custom
			(at 10.349992 -4.100068 180)
			(size 0.1143 0.1143)
			(layers "B.Cu" "B.Mask" "B.Paste")
			(net "M_B_DQ32")
			(options
				(clearance outline)
				(anchor circle)
			)
			(primitives
				(gr_poly
					(pts
						(xy 0 -0.9017) (xy -0.03175 -0.89916) (xy -0.0635 -0.889) (xy -0.09144 -0.87376) (xy -0.11684 -0.85344)
						(xy -0.13716 -0.82804) (xy -0.1524 -0.8001) (xy -0.16256 -0.76835) (xy -0.1651 -0.7366) (xy -0.1651 -0.44958)
						(xy -0.17272 -0.44196) (xy -0.19812 -0.4064) (xy -0.2032 -0.39624) (xy -0.20701 -0.38735) (xy -0.21209 -0.37719)
						(xy -0.2159 -0.36703) (xy -0.21844 -0.35687) (xy -0.22225 -0.34544) (xy -0.22352 -0.33528) (xy -0.22606 -0.32512)
						(xy -0.22733 -0.31369) (xy -0.22733 -0.30353) (xy -0.2286 -0.2921) (xy -0.22733 -0.28067) (xy -0.22733 -0.27051)
						(xy -0.22606 -0.25908) (xy -0.22352 -0.24892) (xy -0.22225 -0.23876) (xy -0.21844 -0.22733) (xy -0.2159 -0.21717)
						(xy -0.21209 -0.20701) (xy -0.20701 -0.19685) (xy -0.2032 -0.18796) (xy -0.19812 -0.1778) (xy -0.17272 -0.14224)
						(xy -0.1651 -0.13462) (xy -0.1651 0.7366) (xy -0.16256 0.76835) (xy -0.1524 0.8001) (xy -0.13716 0.82804)
						(xy -0.11684 0.85344) (xy -0.09144 0.87376) (xy -0.0635 0.889) (xy -0.03175 0.89916) (xy 0 0.9017)
						(xy 0.03175 0.89916) (xy 0.0635 0.889) (xy 0.09144 0.87376) (xy 0.11684 0.85344) (xy 0.13716 0.82804)
						(xy 0.1524 0.8001) (xy 0.16256 0.76835) (xy 0.1651 0.7366) (xy 0.1651 -0.13462) (xy 0.17272 -0.14224)
						(xy 0.19812 -0.1778) (xy 0.2032 -0.18796) (xy 0.20701 -0.19685) (xy 0.21209 -0.20701) (xy 0.2159 -0.21717)
						(xy 0.21844 -0.22733) (xy 0.22225 -0.23876) (xy 0.22352 -0.24892) (xy 0.22606 -0.25908) (xy 0.22733 -0.27051)
						(xy 0.22733 -0.28067) (xy 0.2286 -0.2921) (xy 0.22733 -0.30353) (xy 0.22733 -0.31369) (xy 0.22606 -0.32512)
						(xy 0.22352 -0.33528) (xy 0.22225 -0.34544) (xy 0.21844 -0.35687) (xy 0.2159 -0.36703) (xy 0.21209 -0.37719)
						(xy 0.20701 -0.38735) (xy 0.2032 -0.39624) (xy 0.19812 -0.4064) (xy 0.17272 -0.44196) (xy 0.1651 -0.44958)
						(xy 0.1651 -0.7366) (xy 0.16256 -0.76835) (xy 0.1524 -0.8001) (xy 0.13716 -0.82804) (xy 0.11684 -0.85344)
						(xy 0.09144 -0.87376) (xy 0.0635 -0.889) (xy 0.03175 -0.89916)
					)
					(width 0)
					(fill yes)
				)
			)
		)
		(pad "134" smd custom
			(at 10.649966 4.100068 180)
			(size 0.1143 0.1143)
			(layers "B.Cu" "B.Mask" "B.Paste")
			(net "M_B_DQ36")
			(options
				(clearance outline)
				(anchor circle)
			)
			(primitives
				(gr_poly
					(pts
						(xy 0 -0.9017) (xy -0.03175 -0.89916) (xy -0.0635 -0.889) (xy -0.09144 -0.87376) (xy -0.11684 -0.85344)
						(xy -0.13716 -0.82804) (xy -0.1524 -0.8001) (xy -0.16256 -0.76835) (xy -0.1651 -0.7366) (xy -0.1651 0.13462)
						(xy -0.17272 0.14224) (xy -0.19812 0.1778) (xy -0.2032 0.18796) (xy -0.20701 0.19685) (xy -0.21209 0.20701)
						(xy -0.2159 0.21717) (xy -0.21844 0.22733) (xy -0.22225 0.23876) (xy -0.22352 0.24892) (xy -0.22606 0.25908)
						(xy -0.22733 0.27051) (xy -0.22733 0.28067) (xy -0.2286 0.2921) (xy -0.22733 0.30353) (xy -0.22733 0.31369)
						(xy -0.22606 0.32512) (xy -0.22352 0.33528) (xy -0.22225 0.34544) (xy -0.21844 0.35687) (xy -0.2159 0.36703)
						(xy -0.21209 0.37719) (xy -0.20701 0.38735) (xy -0.2032 0.39624) (xy -0.19812 0.4064) (xy -0.17272 0.44196)
						(xy -0.1651 0.44958) (xy -0.1651 0.7366) (xy -0.16256 0.76835) (xy -0.1524 0.8001) (xy -0.13716 0.82804)
						(xy -0.11684 0.85344) (xy -0.09144 0.87376) (xy -0.0635 0.889) (xy -0.03175 0.89916) (xy 0 0.9017)
						(xy 0.03175 0.89916) (xy 0.0635 0.889) (xy 0.09144 0.87376) (xy 0.11684 0.85344) (xy 0.13716 0.82804)
						(xy 0.1524 0.8001) (xy 0.16256 0.76835) (xy 0.1651 0.7366) (xy 0.1651 0.44958) (xy 0.17272 0.44196)
						(xy 0.19812 0.4064) (xy 0.2032 0.39624) (xy 0.20701 0.38735) (xy 0.21209 0.37719) (xy 0.2159 0.36703)
						(xy 0.21844 0.35687) (xy 0.22225 0.34544) (xy 0.22352 0.33528) (xy 0.22606 0.32512) (xy 0.22733 0.31369)
						(xy 0.22733 0.30353) (xy 0.2286 0.2921) (xy 0.22733 0.28067) (xy 0.22733 0.27051) (xy 0.22606 0.25908)
						(xy 0.22352 0.24892) (xy 0.22225 0.23876) (xy 0.21844 0.22733) (xy 0.2159 0.21717) (xy 0.21209 0.20701)
						(xy 0.20701 0.19685) (xy 0.2032 0.18796) (xy 0.19812 0.1778) (xy 0.17272 0.14224) (xy 0.1651 0.13462)
						(xy 0.1651 -0.7366) (xy 0.16256 -0.76835) (xy 0.1524 -0.8001) (xy 0.13716 -0.82804) (xy 0.11684 -0.85344)
						(xy 0.09144 -0.87376) (xy 0.0635 -0.889) (xy 0.03175 -0.89916)
					)
					(width 0)
					(fill yes)
				)
			)
		)
		(pad "135" smd custom
			(at 10.94994 -4.100068 180)
			(size 0.1143 0.1143)
			(layers "B.Cu" "B.Mask" "B.Paste")
			(net "M_B_DQ33")
			(options
				(clearance outline)
				(anchor circle)
			)
			(primitives
				(gr_poly
					(pts
						(xy 0 -0.9017) (xy -0.03175 -0.89916) (xy -0.0635 -0.889) (xy -0.09144 -0.87376) (xy -0.11684 -0.85344)
						(xy -0.13716 -0.82804) (xy -0.1524 -0.8001) (xy -0.16256 -0.76835) (xy -0.1651 -0.7366) (xy -0.1651 -0.19685)
						(xy -0.17272 -0.18923) (xy -0.17907 -0.18034) (xy -0.18669 -0.17145) (xy -0.19177 -0.16256) (xy -0.19812 -0.15367)
						(xy -0.20828 -0.13335) (xy -0.21971 -0.10287) (xy -0.22225 -0.09271) (xy -0.22479 -0.08128) (xy -0.22606 -0.07112)
						(xy -0.2286 -0.05969) (xy -0.2286 -0.01651) (xy -0.22606 -0.00508) (xy -0.22479 0.00508) (xy -0.22225 0.01651)
						(xy -0.21971 0.02667) (xy -0.20828 0.05715) (xy -0.19812 0.07747) (xy -0.19177 0.08636) (xy -0.18669 0.09525)
						(xy -0.17907 0.10414) (xy -0.17272 0.11303) (xy -0.1651 0.12065) (xy -0.1651 0.7366) (xy -0.16256 0.76835)
						(xy -0.1524 0.8001) (xy -0.13716 0.82804) (xy -0.11684 0.85344) (xy -0.09144 0.87376) (xy -0.0635 0.889)
						(xy -0.03175 0.89916) (xy 0 0.9017) (xy 0.03175 0.89916) (xy 0.0635 0.889) (xy 0.09144 0.87376)
						(xy 0.11684 0.85344) (xy 0.13716 0.82804) (xy 0.1524 0.8001) (xy 0.16256 0.76835) (xy 0.1651 0.7366)
						(xy 0.1651 0.11938) (xy 0.17272 0.11176) (xy 0.19812 0.0762) (xy 0.2032 0.06604) (xy 0.20701 0.05715)
						(xy 0.21209 0.04699) (xy 0.2159 0.03683) (xy 0.21844 0.02667) (xy 0.22225 0.01524) (xy 0.22352 0.00508)
						(xy 0.22606 -0.00508) (xy 0.22733 -0.01651) (xy 0.22733 -0.02667) (xy 0.2286 -0.0381) (xy 0.22733 -0.04953)
						(xy 0.22733 -0.05969) (xy 0.22606 -0.07112) (xy 0.22352 -0.08128) (xy 0.22225 -0.09144) (xy 0.21844 -0.10287)
						(xy 0.2159 -0.11303) (xy 0.21209 -0.12319) (xy 0.20701 -0.13335) (xy 0.2032 -0.14224) (xy 0.19812 -0.1524)
						(xy 0.17272 -0.18796) (xy 0.1651 -0.19558) (xy 0.1651 -0.7366) (xy 0.16256 -0.76835) (xy 0.1524 -0.8001)
						(xy 0.13716 -0.82804) (xy 0.11684 -0.85344) (xy 0.09144 -0.87376) (xy 0.0635 -0.889) (xy 0.03175 -0.89916)
					)
					(width 0)
					(fill yes)
				)
			)
		)
		(pad "136" smd custom
			(at 11.249914 4.100068 180)
			(size 0.1143 0.1143)
			(layers "B.Cu" "B.Mask" "B.Paste")
			(net "M_B_DQ37")
			(options
				(clearance outline)
				(anchor circle)
			)
			(primitives
				(gr_poly
					(pts
						(xy 0 -0.9017) (xy -0.03175 -0.89916) (xy -0.0635 -0.889) (xy -0.09144 -0.87376) (xy -0.11684 -0.85344)
						(xy -0.13716 -0.82804) (xy -0.1524 -0.8001) (xy -0.16256 -0.76835) (xy -0.1651 -0.7366) (xy -0.1651 -0.11938)
						(xy -0.17272 -0.11176) (xy -0.19812 -0.0762) (xy -0.2032 -0.06604) (xy -0.20701 -0.05715) (xy -0.21209 -0.04699)
						(xy -0.2159 -0.03683) (xy -0.21844 -0.02667) (xy -0.22225 -0.01524) (xy -0.22352 -0.00508) (xy -0.22606 0.00508)
						(xy -0.22733 0.01651) (xy -0.22733 0.02667) (xy -0.2286 0.0381) (xy -0.22733 0.04953) (xy -0.22733 0.05969)
						(xy -0.22606 0.07112) (xy -0.22352 0.08128) (xy -0.22225 0.09144) (xy -0.21844 0.10287) (xy -0.2159 0.11303)
						(xy -0.21209 0.12319) (xy -0.20701 0.13335) (xy -0.2032 0.14224) (xy -0.19812 0.1524) (xy -0.17272 0.18796)
						(xy -0.1651 0.19558) (xy -0.1651 0.7366) (xy -0.16256 0.76835) (xy -0.1524 0.8001) (xy -0.13716 0.82804)
						(xy -0.11684 0.85344) (xy -0.09144 0.87376) (xy -0.0635 0.889) (xy -0.03175 0.89916) (xy 0 0.9017)
						(xy 0.03175 0.89916) (xy 0.0635 0.889) (xy 0.09144 0.87376) (xy 0.11684 0.85344) (xy 0.13716 0.82804)
						(xy 0.1524 0.8001) (xy 0.16256 0.76835) (xy 0.1651 0.7366) (xy 0.1651 0.19685) (xy 0.17272 0.18923)
						(xy 0.17907 0.18034) (xy 0.18669 0.17145) (xy 0.19177 0.16256) (xy 0.19812 0.15367) (xy 0.20828 0.13335)
						(xy 0.21971 0.10287) (xy 0.22225 0.09271) (xy 0.22479 0.08128) (xy 0.22606 0.07112) (xy 0.2286 0.05969)
						(xy 0.2286 0.01651) (xy 0.22606 0.00508) (xy 0.22479 -0.00508) (xy 0.22225 -0.01651) (xy 0.21971 -0.02667)
						(xy 0.20828 -0.05715) (xy 0.19812 -0.07747) (xy 0.19177 -0.08636) (xy 0.18669 -0.09525) (xy 0.17907 -0.10414)
						(xy 0.17272 -0.11303) (xy 0.1651 -0.12065) (xy 0.1651 -0.7366) (xy 0.16256 -0.76835) (xy 0.1524 -0.8001)
						(xy 0.13716 -0.82804) (xy 0.11684 -0.85344) (xy 0.09144 -0.87376) (xy 0.0635 -0.889) (xy 0.03175 -0.89916)
					)
					(width 0)
					(fill yes)
				)
			)
		)
		(pad "137" smd custom
			(at 11.549888 -4.100068 180)
			(size 0.1143 0.1143)
			(layers "B.Cu" "B.Mask" "B.Paste")
			(net "GND")
			(options
				(clearance outline)
				(anchor circle)
			)
			(primitives
				(gr_poly
					(pts
						(xy 0 -0.9017) (xy -0.03175 -0.89916) (xy -0.0635 -0.889) (xy -0.09144 -0.87376) (xy -0.11684 -0.85344)
						(xy -0.13716 -0.82804) (xy -0.1524 -0.8001) (xy -0.16256 -0.76835) (xy -0.1651 -0.7366) (xy -0.1651 -0.44958)
						(xy -0.17272 -0.44196) (xy -0.19812 -0.4064) (xy -0.2032 -0.39624) (xy -0.20701 -0.38735) (xy -0.21209 -0.37719)
						(xy -0.2159 -0.36703) (xy -0.21844 -0.35687) (xy -0.22225 -0.34544) (xy -0.22352 -0.33528) (xy -0.22606 -0.32512)
						(xy -0.22733 -0.31369) (xy -0.22733 -0.30353) (xy -0.2286 -0.2921) (xy -0.22733 -0.28067) (xy -0.22733 -0.27051)
						(xy -0.22606 -0.25908) (xy -0.22352 -0.24892) (xy -0.22225 -0.23876) (xy -0.21844 -0.22733) (xy -0.2159 -0.21717)
						(xy -0.21209 -0.20701) (xy -0.20701 -0.19685) (xy -0.2032 -0.18796) (xy -0.19812 -0.1778) (xy -0.17272 -0.14224)
						(xy -0.1651 -0.13462) (xy -0.1651 0.7366) (xy -0.16256 0.76835) (xy -0.1524 0.8001) (xy -0.13716 0.82804)
						(xy -0.11684 0.85344) (xy -0.09144 0.87376) (xy -0.0635 0.889) (xy -0.03175 0.89916) (xy 0 0.9017)
						(xy 0.03175 0.89916) (xy 0.0635 0.889) (xy 0.09144 0.87376) (xy 0.11684 0.85344) (xy 0.13716 0.82804)
						(xy 0.1524 0.8001) (xy 0.16256 0.76835) (xy 0.1651 0.7366) (xy 0.1651 -0.13462) (xy 0.17272 -0.14224)
						(xy 0.19812 -0.1778) (xy 0.2032 -0.18796) (xy 0.20701 -0.19685) (xy 0.21209 -0.20701) (xy 0.2159 -0.21717)
						(xy 0.21844 -0.22733) (xy 0.22225 -0.23876) (xy 0.22352 -0.24892) (xy 0.22606 -0.25908) (xy 0.22733 -0.27051)
						(xy 0.22733 -0.28067) (xy 0.2286 -0.2921) (xy 0.22733 -0.30353) (xy 0.22733 -0.31369) (xy 0.22606 -0.32512)
						(xy 0.22352 -0.33528) (xy 0.22225 -0.34544) (xy 0.21844 -0.35687) (xy 0.2159 -0.36703) (xy 0.21209 -0.37719)
						(xy 0.20701 -0.38735) (xy 0.2032 -0.39624) (xy 0.19812 -0.4064) (xy 0.17272 -0.44196) (xy 0.1651 -0.44958)
						(xy 0.1651 -0.7366) (xy 0.16256 -0.76835) (xy 0.1524 -0.8001) (xy 0.13716 -0.82804) (xy 0.11684 -0.85344)
						(xy 0.09144 -0.87376) (xy 0.0635 -0.889) (xy 0.03175 -0.89916)
					)
					(width 0)
					(fill yes)
				)
			)
		)
		(pad "138" smd custom
			(at 11.850116 4.100068 180)
			(size 0.1143 0.1143)
			(layers "B.Cu" "B.Mask" "B.Paste")
			(net "GND")
			(options
				(clearance outline)
				(anchor circle)
			)
			(primitives
				(gr_poly
					(pts
						(xy 0 -0.9017) (xy -0.03175 -0.89916) (xy -0.0635 -0.889) (xy -0.09144 -0.87376) (xy -0.11684 -0.85344)
						(xy -0.13716 -0.82804) (xy -0.1524 -0.8001) (xy -0.16256 -0.76835) (xy -0.1651 -0.7366) (xy -0.1651 0.13462)
						(xy -0.17272 0.14224) (xy -0.19812 0.1778) (xy -0.2032 0.18796) (xy -0.20701 0.19685) (xy -0.21209 0.20701)
						(xy -0.2159 0.21717) (xy -0.21844 0.22733) (xy -0.22225 0.23876) (xy -0.22352 0.24892) (xy -0.22606 0.25908)
						(xy -0.22733 0.27051) (xy -0.22733 0.28067) (xy -0.2286 0.2921) (xy -0.22733 0.30353) (xy -0.22733 0.31369)
						(xy -0.22606 0.32512) (xy -0.22352 0.33528) (xy -0.22225 0.34544) (xy -0.21844 0.35687) (xy -0.2159 0.36703)
						(xy -0.21209 0.37719) (xy -0.20701 0.38735) (xy -0.2032 0.39624) (xy -0.19812 0.4064) (xy -0.17272 0.44196)
						(xy -0.1651 0.44958) (xy -0.1651 0.7366) (xy -0.16256 0.76835) (xy -0.1524 0.8001) (xy -0.13716 0.82804)
						(xy -0.11684 0.85344) (xy -0.09144 0.87376) (xy -0.0635 0.889) (xy -0.03175 0.89916) (xy 0 0.9017)
						(xy 0.03175 0.89916) (xy 0.0635 0.889) (xy 0.09144 0.87376) (xy 0.11684 0.85344) (xy 0.13716 0.82804)
						(xy 0.1524 0.8001) (xy 0.16256 0.76835) (xy 0.1651 0.7366) (xy 0.1651 0.44958) (xy 0.17272 0.44196)
						(xy 0.19812 0.4064) (xy 0.2032 0.39624) (xy 0.20701 0.38735) (xy 0.21209 0.37719) (xy 0.2159 0.36703)
						(xy 0.21844 0.35687) (xy 0.22225 0.34544) (xy 0.22352 0.33528) (xy 0.22606 0.32512) (xy 0.22733 0.31369)
						(xy 0.22733 0.30353) (xy 0.2286 0.2921) (xy 0.22733 0.28067) (xy 0.22733 0.27051) (xy 0.22606 0.25908)
						(xy 0.22352 0.24892) (xy 0.22225 0.23876) (xy 0.21844 0.22733) (xy 0.2159 0.21717) (xy 0.21209 0.20701)
						(xy 0.20701 0.19685) (xy 0.2032 0.18796) (xy 0.19812 0.1778) (xy 0.17272 0.14224) (xy 0.1651 0.13462)
						(xy 0.1651 -0.7366) (xy 0.16256 -0.76835) (xy 0.1524 -0.8001) (xy 0.13716 -0.82804) (xy 0.11684 -0.85344)
						(xy 0.09144 -0.87376) (xy 0.0635 -0.889) (xy 0.03175 -0.89916)
					)
					(width 0)
					(fill yes)
				)
			)
		)
		(pad "139" smd custom
			(at 12.15009 -4.100068 180)
			(size 0.1143 0.1143)
			(layers "B.Cu" "B.Mask" "B.Paste")
			(net "M_B_DQS_DN4")
			(options
				(clearance outline)
				(anchor circle)
			)
			(primitives
				(gr_poly
					(pts
						(xy 0 -0.9017) (xy -0.03175 -0.89916) (xy -0.0635 -0.889) (xy -0.09144 -0.87376) (xy -0.11684 -0.85344)
						(xy -0.13716 -0.82804) (xy -0.1524 -0.8001) (xy -0.16256 -0.76835) (xy -0.1651 -0.7366) (xy -0.1651 -0.19685)
						(xy -0.17272 -0.18923) (xy -0.17907 -0.18034) (xy -0.18669 -0.17145) (xy -0.19177 -0.16256) (xy -0.19812 -0.15367)
						(xy -0.20828 -0.13335) (xy -0.21971 -0.10287) (xy -0.22225 -0.09271) (xy -0.22479 -0.08128) (xy -0.22606 -0.07112)
						(xy -0.2286 -0.05969) (xy -0.2286 -0.01651) (xy -0.22606 -0.00508) (xy -0.22479 0.00508) (xy -0.22225 0.01651)
						(xy -0.21971 0.02667) (xy -0.20828 0.05715) (xy -0.19812 0.07747) (xy -0.19177 0.08636) (xy -0.18669 0.09525)
						(xy -0.17907 0.10414) (xy -0.17272 0.11303) (xy -0.1651 0.12065) (xy -0.1651 0.7366) (xy -0.16256 0.76835)
						(xy -0.1524 0.8001) (xy -0.13716 0.82804) (xy -0.11684 0.85344) (xy -0.09144 0.87376) (xy -0.0635 0.889)
						(xy -0.03175 0.89916) (xy 0 0.9017) (xy 0.03175 0.89916) (xy 0.0635 0.889) (xy 0.09144 0.87376)
						(xy 0.11684 0.85344) (xy 0.13716 0.82804) (xy 0.1524 0.8001) (xy 0.16256 0.76835) (xy 0.1651 0.7366)
						(xy 0.1651 0.11938) (xy 0.17272 0.11176) (xy 0.19812 0.0762) (xy 0.2032 0.06604) (xy 0.20701 0.05715)
						(xy 0.21209 0.04699) (xy 0.2159 0.03683) (xy 0.21844 0.02667) (xy 0.22225 0.01524) (xy 0.22352 0.00508)
						(xy 0.22606 -0.00508) (xy 0.22733 -0.01651) (xy 0.22733 -0.02667) (xy 0.2286 -0.0381) (xy 0.22733 -0.04953)
						(xy 0.22733 -0.05969) (xy 0.22606 -0.07112) (xy 0.22352 -0.08128) (xy 0.22225 -0.09144) (xy 0.21844 -0.10287)
						(xy 0.2159 -0.11303) (xy 0.21209 -0.12319) (xy 0.20701 -0.13335) (xy 0.2032 -0.14224) (xy 0.19812 -0.1524)
						(xy 0.17272 -0.18796) (xy 0.1651 -0.19558) (xy 0.1651 -0.7366) (xy 0.16256 -0.76835) (xy 0.1524 -0.8001)
						(xy 0.13716 -0.82804) (xy 0.11684 -0.85344) (xy 0.09144 -0.87376) (xy 0.0635 -0.889) (xy 0.03175 -0.89916)
					)
					(width 0)
					(fill yes)
				)
			)
		)
	)
)
